FILE_TYPE = CONNECTIVITY;
{Allegro Design Entry HDL 17.2-2016 S081 (4005846) 1/11/2022}
"PAGE_NUMBER" = 150;
0"NC";
1"P3V3_OCP_SFF\g";
2"P3V3_OCP_SFF\g";
3"P12V_OCP_SFF\g";
4"P12V_OCP_SFF\g";
5"P3V3_OCP_SFF\g";
6"P3V3_OCP_SFF\g";
7"GND\g";
8"GND\g";
9"GND\g";
10"GND\g";
11"GND\g";
12"GND\g";
13"GND\g";
14"GND\g";
15"GND\g";
16"P5E_CPU0_PE1_RX_DP<15:0>";
17"P5E_CPU0_PE1_RX_DN<15:0>";
18"P5E_CPU0_PE1_TX_C_DN<15:0>";
19"P5E_CPU0_PE1_TX_C_DP<15:0>";
20"CLK_100M_OCP_SFF_3_DN";
21"CLK_100M_OCP_SFF_3_DP";
22"CLK_50M_NCSI_OCP_SFF_ISO";
23"SMB_OCP_SFF_3V3AUX_BUF_SCL";
24"SMB_OCP_SFF_3V3AUX_BUF_SDA";
25"RST_SMB_OCP_SFF_N";
26"OCP_SFF_MAIN_PWR_EN_R";
27"FM_OCP_SFF_PWR_GOOD";
28"RST_PERST2_OCP_SFF_N";
29"RST_PERST3_OCP_SFF_N";
30"IRQ_LVC3_OCP_SFF_WAKE_N";
31"SMB_OCP_SFF_3V3AUX_BUF_R_SDA";
32"RST_PERST0_OCP_SFF_N";
33"OCP_SFF_AUX_PWR_EN";
34"OCP_SFF_AUX_PWR_EN"CDS_PHYS_NET_NAME"OCP_SFF_AUX_PWR_EN";
35"OCP_SFF_ID1";
36"OCP_SFF_ID0";
37"P5E_CPU0_PE1_RX_DN<12>";
38"P5E_CPU0_PE1_RX_DP<11>";
39"P5E_CPU0_PE1_RX_DN<3>";
40"SMB_OCP_SFF_3V3AUX_BUF_R_SCL";
41"P5E_CPU0_PE1_RX_DN<4>";
42"P5E_CPU0_PE1_TX_C_DN<14>";
43"P5E_CPU0_PE1_RX_DN<6>";
44"P5E_CPU0_PE1_RX_DN<5>";
45"CLK_100M_OCP_SFF_1_DP";
46"P5E_CPU0_PE1_TX_C_DN<13>"$PNN"P5E_CPU0_PE1_TX_C_DN<13>";
47"P5E_CPU0_PE1_RX_DP<5>";
48"P5E_CPU0_PE1_RX_DP<6>";
49"P5E_CPU0_PE1_RX_DN<11>";
50"OCP_SFF_USB2_3_DP";
51"OCP_SFF_PWRBRK_N";
52"P5E_CPU0_PE1_RX_DP<12>";
53"P5E_CPU0_PE1_RX_DN<13>";
54"P5E_CPU0_PE1_RX_DN<10>";
55"P5E_CPU0_PE1_RX_DP<10>";
56"P5E_CPU0_PE1_RX_DN<9>";
57"P5E_CPU0_PE1_RX_DP<9>";
58"P5E_CPU0_PE1_RX_DN<8>";
59"P5E_CPU0_PE1_RX_DP<8>";
60"P5E_CPU0_PE1_RX_DN<7>";
61"P5E_CPU0_PE1_RX_DP<7>";
62"P5E_CPU0_PE1_RX_DN<1>";
63"P5E_CPU0_PE1_RX_DP<1>";
64"P5E_CPU0_PE1_RX_DP<3>";
65"P5E_CPU0_PE1_RX_DP<13>";
66"P5E_CPU0_PE1_RX_DN<0>";
67"P5E_CPU0_PE1_RX_DP<0>";
68"P5E_CPU0_PE1_TX_C_DN<5>";
69"P5E_CPU0_PE1_TX_C_DN<12>";
70"P5E_CPU0_PE1_TX_C_DP<12>";
71"P5E_CPU0_PE1_RX_DP<14>";
72"P5E_CPU0_PE1_RX_DN<14>";
73"OCP_SFF_USB2_3_DN";
74"P5E_CPU0_PE1_RX_DN<15>";
75"P5E_CPU0_PE1_RX_DP<15>";
76"P5E_CPU0_PE1_TX_C_DN<9>";
77"P5E_CPU0_PE1_TX_C_DP<10>";
78"P5E_CPU0_PE1_TX_C_DN<10>";
79"P5E_CPU0_PE1_TX_C_DN<11>";
80"P5E_CPU0_PE1_TX_C_DP<13>";
81"P5E_CPU0_PE1_TX_C_DP<11>";
82"P5E_CPU0_PE1_TX_C_DP<14>";
83"P5E_CPU0_PE1_TX_C_DN<15>"$PNN"P5E_CPU0_PE1_TX_C_DN<15>";
84"TP_OCP_SFF_B69";
85"TP_OCP_SFF_B68";
86"P5E_CPU0_PE1_TX_C_DP<15>";
87"USB2_3_DP";
88"USB2_3_DN";
89"OCP_SFF_PRSNT1_R_N";
90"CLK_100M_OCP_SFF_1_DN";
91"OCP_SFF_PRSNT2_R_N";
92"RST_PERST1_OCP_SFF_N";
93"OCP_SFF_PRSNTA_R_N";
94"NCSI_OCP_SFF_TXD1";
95"P5E_CPU0_PE1_TX_C_DP<8>";
96"P5E_CPU0_PE1_TX_C_DN<8>";
97"P5E_CPU0_PE1_TX_C_DP<9>";
98"OCP_SFF_PRSNT3_R_N";
99"SGPIO_OCP_SFF_DATAIN";
100"SGPIO_OCP_SFF_LD_N";
101"P5E_CPU0_PE1_TX_C_DP<6>";
102"P5E_CPU0_PE1_TX_C_DP<2>";
103"P5E_CPU0_PE1_TX_C_DP<1>";
104"P5E_CPU0_PE1_TX_C_DN<2>";
105"P5E_CPU0_PE1_TX_C_DN<3>";
106"P5E_CPU0_PE1_TX_C_DP<3>";
107"P5E_CPU0_PE1_TX_C_DN<4>";
108"P5E_CPU0_PE1_TX_C_DP<5>";
109"P5E_CPU0_PE1_TX_C_DN<6>";
110"P5E_CPU0_PE1_TX_C_DN<7>";
111"OCP_SFF_PRSNT0_R_N";
112"P5E_CPU0_PE1_TX_C_DP<7>";
113"P5E_CPU0_PE1_RX_DP<4>";
114"P5E_CPU0_PE1_TX_C_DP<4>";
115"P5E_CPU0_PE1_TX_C_DN<1>";
116"P5E_CPU0_PE1_TX_C_DP<0>";
117"P5E_CPU0_PE1_TX_C_DN<0>";
118"OCP_SFF_ISO1_RBT_ARB_IN";
119"OCP_SFF_ID1";
120"NCSI_OCP_SFF_TX_EN";
121"NCSI_OCP_SFF_TXD0";
122"OCP_SFF_ISO2_RBT_ARB_OUT";
123"P5E_CPU0_PE1_RX_DN<2>";
124"P5E_CPU0_PE1_RX_DP<2>";
125"OCP_SFF_ISO_BIF0_EN";
126"CLK_100M_OCP_SFF_0_DN";
127"OCP_SFF_ISO_BIF1_EN";
128"OCP_SFF_ISO_BIF2_EN";
129"CLK_100M_OCP_SFF_0_DP";
130"OCP_SFF_BIF1_R_N";
131"OCP_SFF_BIF2_R_N";
132"FM_OCP_SFF_PWR_GOOD"CDS_PHYS_NET_NAME"FM_OCP_SFF_PWR_GOOD";
133"OCP_SFF_AUX_PWR_EN_R";
134"NCSI_OCP_SFF_RXD1";
135"NCSI_OCP_SFF_RXD0";
136"CLK_100M_OCP_SFF_2_DN";
137"CLK_100M_OCP_SFF_2_DP";
138"NCSI_OCP_SFF_CRS_DV";
139"OCP_SFF_ID0";
140"SGPIO_OCP_SFF_CLK";
141"SGPIO_OCP_SFF_DATAOUT";
142"SGPIO_OCP_SFF_DATAIN";
143"SGPIO_OCP_SFF_LD_N";
144"OCP_SFF_MAIN_PWR_EN";
145"OCP_SFF_MAIN_PWR_EN"CDS_PHYS_NET_NAME"OCP_SFF_MAIN_PWR_EN";
146"OCP_SFF_BIF0_R_N";
147"SGPIO_OCP_SFF_DATAOUT";
148"SGPIO_OCP_SFF_CLK";
%"UNIVERSAL_GND"
"1","(-4325,1500)","0","logical_power","I1";
;
CDS_LIB"logical_power"
HDL_POWER"GND"
ROOM"IO_SLOT";
"A"9;
%"TAP"
"1","(750,3450)","0","standard","I100";
;
CDS_LIB"standard"
BODY_TYPE"PLUMBING"
HDL_TAP"TRUE";
"B \NAC \NWC"17;
"S \NAC"
BN"11"49;
%"TAP"
"1","(750,3600)","0","standard","I101";
;
CDS_LIB"standard"
BODY_TYPE"PLUMBING"
HDL_TAP"TRUE";
"B \NAC \NWC"17;
"S \NAC"
BN"10"54;
%"TAP"
"1","(750,3750)","0","standard","I102";
;
CDS_LIB"standard"
BODY_TYPE"PLUMBING"
HDL_TAP"TRUE";
"B \NAC \NWC"17;
"S \NAC"
BN"9"56;
%"TAP"
"1","(750,3900)","0","standard","I103";
;
CDS_LIB"standard"
BODY_TYPE"PLUMBING"
HDL_TAP"TRUE";
"B \NAC \NWC"17;
"S \NAC"
BN"8"58;
%"TAP"
"1","(900,3050)","0","standard","I104";
;
CDS_LIB"standard"
BODY_TYPE"PLUMBING"
HDL_TAP"TRUE";
"B \NAC \NWC"16;
"S \NAC"
BN"14"71;
%"TAP"
"1","(900,3350)","0","standard","I105";
;
CDS_LIB"standard"
BODY_TYPE"PLUMBING"
HDL_TAP"TRUE";
"B \NAC \NWC"16;
"S \NAC"
BN"12"52;
%"TAP"
"1","(900,3200)","0","standard","I106";
;
CDS_LIB"standard"
BODY_TYPE"PLUMBING"
HDL_TAP"TRUE";
"B \NAC \NWC"16;
"S \NAC"
BN"13"65;
%"TAP"
"1","(900,3650)","0","standard","I107";
;
CDS_LIB"standard"
BODY_TYPE"PLUMBING"
HDL_TAP"TRUE";
"B \NAC \NWC"16;
"S \NAC"
BN"10"55;
%"TAP"
"1","(900,3500)","0","standard","I108";
;
CDS_LIB"standard"
BODY_TYPE"PLUMBING"
HDL_TAP"TRUE";
"B \NAC \NWC"16;
"S \NAC"
BN"11"38;
%"TAP"
"1","(900,3800)","0","standard","I109";
;
CDS_LIB"standard"
BODY_TYPE"PLUMBING"
HDL_TAP"TRUE";
"B \NAC \NWC"16;
"S \NAC"
BN"9"57;
%"Q_CAP"
"1","(1750,1750)","0","pure_quanta","I110";
;
PART_NUMBER"CH4104K1B00"
MATERIAL"X7R"
PACK_TYPE"0402"
VOLTAGE"25V"
VALUE"0.1UF"
TOLERANCE"10%"
$LOCATION"C1234"
CDS_LIB"pure_quanta"
CDS_LOCATION"C1234"
$SEC"1"
CDS_SEC"1";
"B"
$PN"2"15;
"A"
$PN"1"4;
%"Q_CAP"
"1","(2025,1750)","0","pure_quanta","I111";
;
PART_NUMBER"CH4104K1B00"
MATERIAL"X7R"
PACK_TYPE"0402"
TOLERANCE"10%"
VOLTAGE"25V"
VALUE"0.1UF"
$LOCATION"C1235"
CDS_LIB"pure_quanta"
CDS_LOCATION"C1235"
$SEC"1"
CDS_SEC"1";
"B"
$PN"2"15;
"A"
$PN"1"4;
%"UNIVERSAL_GND"
"1","(2300,1400)","0","logical_power","I112";
;
CDS_LIB"logical_power"
HDL_POWER"GND"
ROOM"IO_SLOT";
"A"15;
%"Q_CAP"
"1","(2300,1750)","0","pure_quanta","I113";
;
PART_NUMBER"CH4104K1B00"
MATERIAL"X7R"
VALUE"0.1UF"
TOLERANCE"10%"
VOLTAGE"25V"
PACK_TYPE"0402"
$LOCATION"C1236"
CDS_LIB"pure_quanta"
CDS_LOCATION"C1236"
$SEC"1"
CDS_SEC"1";
"B"
$PN"2"15;
"A"
$PN"1"4;
%"Q_CAP"
"1","(2825,1900)","0","pure_quanta","I114";
;
PART_NUMBER"CH4104K1B00"
VALUE"0.1UF"
VOLTAGE"25V"
TOLERANCE"10%"
PACK_TYPE"0402"
MATERIAL"X7R"
$LOCATION"C1237"
CDS_LIB"pure_quanta"
CDS_LOCATION"C1237"
$SEC"1"
CDS_SEC"1";
"B"
$PN"2"7;
"A"
$PN"1"2;
%"Q_CAP"
"1","(3075,1900)","0","pure_quanta","I115";
;
PART_NUMBER"CH4104K1B00"
MATERIAL"X7R"
TOLERANCE"10%"
VOLTAGE"25V"
VALUE"0.1UF"
PACK_TYPE"0402"
$LOCATION"C1238"
CDS_LIB"pure_quanta"
CDS_LOCATION"C1238"
$SEC"1"
CDS_SEC"1";
"B"
$PN"2"7;
"A"
$PN"1"2;
%"Q_CAP"
"1","(3350,1900)","0","pure_quanta","I116";
;
PART_NUMBER"CH4104K1B00"
MATERIAL"X7R"
PACK_TYPE"0402"
TOLERANCE"10%"
VOLTAGE"25V"
VALUE"0.1UF"
$LOCATION"C1239"
CDS_LIB"pure_quanta"
CDS_LOCATION"C1239"
$SEC"1"
CDS_SEC"1";
"B"
$PN"2"7;
"A"
$PN"1"2;
%"Q_RES"
"1","(1500,2750)","0","pure_quanta","I118";
;
PART_NUMBER"CS00002JB13"
TOLERANCE"5%"
VALUE"0"
WATTAGE"1/16W"
MATERIAL"CHIP"
PACK_TYPE"0402LF"
$LOCATION"R444"
CDS_LIB"pure_quanta"
CDS_LOCATION"R444"
$SEC"1"
CDS_SEC"1";
"B"
$PN"2"88;
"A"
$PN"1"73;
%"Q_RES"
"1","(1500,2700)","0","pure_quanta","I119";
;
PART_NUMBER"CS00002JB13"
VALUE"0"
TOLERANCE"5%"
PACK_TYPE"0402LF"
$LOCATION"R445"
MATERIAL"CHIP"
WATTAGE"1/16W"
CDS_LIB"pure_quanta"
CDS_LOCATION"R445"
$SEC"1"
CDS_SEC"1";
"B"
$PN"2"87;
"A"
$PN"1"50;
%"UNIVERSAL_POWER"
"1","(2825,2250)","0","logical_power","I120";
;
HDL_POWER"P3V3_OCP_SFF"
CDS_LIB"logical_power";
"A"2;
%"TAP"
"1","(750,4250)","0","standard","I123";
;
CDS_LIB"standard"
BODY_TYPE"PLUMBING"
HDL_TAP"TRUE";
"B \NAC \NWC"17;
"S \NAC"
BN"7"60;
%"TAP"
"1","(750,4400)","0","standard","I124";
;
CDS_LIB"standard"
BODY_TYPE"PLUMBING"
HDL_TAP"TRUE";
"B \NAC \NWC"17;
"S \NAC"
BN"6"43;
%"TAP"
"1","(750,4550)","0","standard","I125";
;
CDS_LIB"standard"
BODY_TYPE"PLUMBING"
HDL_TAP"TRUE";
"B \NAC \NWC"17;
"S \NAC"
BN"5"44;
%"TAP"
"1","(750,4700)","0","standard","I126";
;
CDS_LIB"standard"
BODY_TYPE"PLUMBING"
HDL_TAP"TRUE";
"B \NAC \NWC"17;
"S \NAC"
BN"4"41;
%"TAP"
"1","(900,3950)","0","standard","I127";
;
CDS_LIB"standard"
BODY_TYPE"PLUMBING"
HDL_TAP"TRUE";
"B \NAC \NWC"16;
"S \NAC"
BN"8"59;
%"TAP"
"1","(900,4450)","0","standard","I128";
;
CDS_LIB"standard"
BODY_TYPE"PLUMBING"
HDL_TAP"TRUE";
"B \NAC \NWC"16;
"S \NAC"
BN"6"48;
%"TAP"
"1","(900,4300)","0","standard","I129";
;
CDS_LIB"standard"
BODY_TYPE"PLUMBING"
HDL_TAP"TRUE";
"B \NAC \NWC"16;
"S \NAC"
BN"7"61;
%"TAP"
"1","(900,4600)","0","standard","I130";
;
CDS_LIB"standard"
BODY_TYPE"PLUMBING"
HDL_TAP"TRUE";
"B \NAC \NWC"16;
"S \NAC"
BN"5"47;
%"TAP"
"1","(900,4750)","0","standard","I131";
;
CDS_LIB"standard"
BODY_TYPE"PLUMBING"
HDL_TAP"TRUE";
"B \NAC \NWC"16;
"S \NAC"
BN"4"113;
%"TAP"
"1","(750,5000)","0","standard","I132";
;
CDS_LIB"standard"
BODY_TYPE"PLUMBING"
HDL_TAP"TRUE";
"B \NAC \NWC"17;
"S \NAC"
BN"3"39;
%"TAP"
"1","(750,5150)","0","standard","I133";
;
CDS_LIB"standard"
BODY_TYPE"PLUMBING"
HDL_TAP"TRUE";
"B \NAC \NWC"17;
"S \NAC"
BN"2"123;
%"TAP"
"1","(750,5300)","0","standard","I134";
;
CDS_LIB"standard"
BODY_TYPE"PLUMBING"
HDL_TAP"TRUE";
"B \NAC \NWC"17;
"S \NAC"
BN"1"62;
%"TAP"
"1","(900,5200)","0","standard","I136";
;
CDS_LIB"standard"
BODY_TYPE"PLUMBING"
HDL_TAP"TRUE";
"B \NAC \NWC"16;
"S \NAC"
BN"2"124;
%"TAP"
"1","(900,5050)","0","standard","I137";
;
CDS_LIB"standard"
BODY_TYPE"PLUMBING"
HDL_TAP"TRUE";
"B \NAC \NWC"16;
"S \NAC"
BN"3"64;
%"TAP"
"1","(900,5350)","0","standard","I138";
;
CDS_LIB"standard"
BODY_TYPE"PLUMBING"
HDL_TAP"TRUE";
"B \NAC \NWC"16;
"S \NAC"
BN"1"63;
%"UNIVERSAL_GND"
"1","(3100,5325)","0","logical_power","I148";
;
CDS_LIB"logical_power"
HDL_POWER"GND"
ROOM"IO_SLOT";
"A"13;
%"Q_RES"
"2","(3100,5600)","0","pure_quanta","I149";
;
PART_NUMBER"CS11002FB07"
PACK_TYPE"0402LF"
TOLERANCE"1%"
WATTAGE"1/16W"
MATERIAL"CHIP"
VALUE"100"
$LOCATION"R1895"
CDS_LIB"pure_quanta"
CDS_LOCATION"R1895"
$SEC"1"
CDS_SEC"1";
"A"
$PN"1"93;
"B"
$PN"2"13;
%"Q_RES"
"1","(1750,6000)","0","pure_quanta","I151";
;
PART_NUMBER"CS03322FB03"
MATERIAL"CHIP"
WATTAGE"1/16W"
TOLERANCE"1%"
PACK_TYPE"0402LF"
VALUE"33.2"
$LOCATION"R424"
CDS_LIB"pure_quanta"
CDS_LOCATION"R424"
$SEC"1"
CDS_SEC"1";
"B"
$PN"2"23;
"A"
$PN"1"40;
%"UNIVERSAL_GND"
"1","(3625,1550)","0","logical_power","I167";
;
CDS_LIB"logical_power"
HDL_POWER"GND"
ROOM"IO_SLOT";
"A"7;
%"Q_CAP"
"1","(3625,1900)","0","pure_quanta","I168";
;
PART_NUMBER"CH4104K1B00"
PACK_TYPE"0402"
VALUE"0.1UF"
MATERIAL"X7R"
TOLERANCE"10%"
VOLTAGE"25V"
$LOCATION"C1240"
CDS_LIB"pure_quanta"
CDS_LOCATION"C1240"
$SEC"1"
CDS_SEC"1";
"B"
$PN"2"7;
"A"
$PN"1"2;
%"TAP"
"1","(-1600,3900)","2","standard","I169";
;
CDS_LIB"standard"
BODY_TYPE"PLUMBING"
HDL_TAP"TRUE";
"B \NAC \NWC"18;
"S \NAC"
BN"8"96;
%"TAP"
"1","(-1750,3050)","2","standard","I17";
;
CDS_LIB"standard"
BODY_TYPE"PLUMBING"
HDL_TAP"TRUE";
"B \NAC \NWC"19;
"S \NAC"
BN"14"82;
%"UNIVERSAL_POWER"
"1","(-1450,7400)","0","logical_power","I173";
;
HDL_POWER"P12V_OCP_SFF"
CDS_LIB"logical_power";
"A"3;
%"UNIVERSAL_POWER"
"1","(-2275,6175)","0","logical_power","I174";
;
HDL_POWER"P3V3_OCP_SFF"
CDS_LIB"logical_power";
"A"6;
%"TAP"
"1","(-1600,5350)","2","standard","I176";
;
CDS_LIB"standard"
BODY_TYPE"PLUMBING"
HDL_TAP"TRUE";
"B \NAC \NWC"18;
"S \NAC"
BN"1"115;
%"TAP"
"1","(-1750,5300)","2","standard","I177";
;
CDS_LIB"standard"
BODY_TYPE"PLUMBING"
HDL_TAP"TRUE";
"B \NAC \NWC"19;
"S \NAC"
BN"1"103;
%"TAP"
"1","(-1750,5000)","2","standard","I179";
;
CDS_LIB"standard"
BODY_TYPE"PLUMBING"
HDL_TAP"TRUE";
"B \NAC \NWC"19;
"S \NAC"
BN"3"106;
%"TAP"
"1","(-1600,5050)","2","standard","I180";
;
CDS_LIB"standard"
BODY_TYPE"PLUMBING"
HDL_TAP"TRUE";
"B \NAC \NWC"18;
"S \NAC"
BN"3"105;
%"TAP"
"1","(-1750,4550)","2","standard","I182";
;
CDS_LIB"standard"
BODY_TYPE"PLUMBING"
HDL_TAP"TRUE";
"B \NAC \NWC"19;
"S \NAC"
BN"5"108;
%"TAP"
"1","(-1600,4600)","2","standard","I183";
;
CDS_LIB"standard"
BODY_TYPE"PLUMBING"
HDL_TAP"TRUE";
"B \NAC \NWC"18;
"S \NAC"
BN"5"68;
%"TAP"
"1","(-1750,4250)","2","standard","I185";
;
CDS_LIB"standard"
BODY_TYPE"PLUMBING"
HDL_TAP"TRUE";
"B \NAC \NWC"19;
"S \NAC"
BN"7"112;
%"TAP"
"1","(-1600,4300)","2","standard","I186";
;
CDS_LIB"standard"
BODY_TYPE"PLUMBING"
HDL_TAP"TRUE";
"B \NAC \NWC"18;
"S \NAC"
BN"7"110;
%"TAP"
"1","(-1750,3750)","2","standard","I188";
;
CDS_LIB"standard"
BODY_TYPE"PLUMBING"
HDL_TAP"TRUE";
"B \NAC \NWC"19;
"S \NAC"
BN"9"97;
%"TAP"
"1","(-1600,3800)","2","standard","I189";
;
CDS_LIB"standard"
BODY_TYPE"PLUMBING"
HDL_TAP"TRUE";
"B \NAC \NWC"18;
"S \NAC"
BN"9"76;
%"TAP"
"1","(-1750,3450)","2","standard","I191";
;
CDS_LIB"standard"
BODY_TYPE"PLUMBING"
HDL_TAP"TRUE";
"B \NAC \NWC"19;
"S \NAC"
BN"11"81;
%"TAP"
"1","(-1600,3500)","2","standard","I192";
;
CDS_LIB"standard"
BODY_TYPE"PLUMBING"
HDL_TAP"TRUE";
"B \NAC \NWC"18;
"S \NAC"
BN"11"79;
%"TAP"
"1","(-1750,3150)","2","standard","I194";
;
CDS_LIB"standard"
BODY_TYPE"PLUMBING"
HDL_TAP"TRUE";
"B \NAC \NWC"19;
"S \NAC"
BN"13"80;
%"TAP"
"1","(-1600,3200)","2","standard","I195";
;
CDS_LIB"standard"
BODY_TYPE"PLUMBING"
HDL_TAP"TRUE";
"B \NAC \NWC"18;
"S \NAC"
BN"13"46;
%"TAP"
"1","(-1750,2850)","2","standard","I197";
;
CDS_LIB"standard"
BODY_TYPE"PLUMBING"
HDL_TAP"TRUE";
"B \NAC \NWC"19;
"S \NAC"
BN"15"86;
%"TAP"
"1","(-1600,2900)","2","standard","I198";
;
CDS_LIB"standard"
BODY_TYPE"PLUMBING"
HDL_TAP"TRUE";
"B \NAC \NWC"18;
"S \NAC"
BN"15"83;
%"SCONN168_ME1016810202011"
"1","(-375,4725)","0","pure_quanta","I199";
;
PART_NUMBER"DFHSG8FR011"
PART_TYPE"SMLF"
MATERIAL"IO"
VALUE"SCONN168_ME1016810202011"
LOCATION"J37"
SEC_TYPE""
CDS_LIB"pure_quanta"
CDS_LMAN_SYM_OUTLINE"-500,2475,500,-2475"
NEEDS_NO_SIZE"TRUE"
SEC"1";
"G5"
$PN"G5"14;
"G4"
$PN"G4"14;
"G3"
$PN"G3"14;
"G2"
$PN"G2"14;
"G1"
$PN"G1"14;
"PRSNTB3# \B"
$PN"B70"98;
"RFU1_NC_B69"
$PN"B69"84;
"RFU1_NC_B68"
$PN"B68"85;
"GND_B67"
$PN"B67"12;
"PETP15"
$PN"B66"86;
"PETN15"
$PN"B65"83;
"GND_B64"
$PN"B64"12;
"PETP14"
$PN"B63"42;
"PETN14"
$PN"B62"82;
"GND_B61"
$PN"B61"12;
"PETP13"
$PN"B60"80;
"PETN13"
$PN"B59"46;
"GND_B58"
$PN"B58"12;
"PETP12"
$PN"B57"69;
"PWRBRK0# \B"
$PN"A70"51;
"USB_DATP"
$PN"A69"50;
"USB_DATN"
$PN"A68"73;
"GND_A67"
$PN"A67"14;
"PERP15"
$PN"A66"74;
"PERN15"
$PN"A65"75;
"GND_A64"
$PN"A64"14;
"PERP14"
$PN"A63"72;
"PERN14"
$PN"A62"71;
"GND_A61"
$PN"A61"14;
"PERP13"
$PN"A60"53;
"PERN13"
$PN"A59"65;
"GND_A58"
$PN"A58"14;
"PERP12"
$PN"A57"37;
"PERN12"
$PN"A56"52;
"GND_A55"
$PN"A55"14;
"PERP11"
$PN"A54"49;
"PERN11"
$PN"A53"38;
"GND_A52"
$PN"A52"14;
"PERP10"
$PN"A51"54;
"PERN10"
$PN"A50"55;
"GND_A49"
$PN"A49"14;
"PERP9"
$PN"A48"56;
"PERN9"
$PN"A47"57;
"GND_A46"
$PN"A46"14;
"PERP8"
$PN"A45"58;
"PERN8"
$PN"A44"59;
"GND_A43"
$PN"A43"14;
"PRSNTB1# \B"
$PN"A42"89;
"GND_A41"
$PN"A41"14;
"PERP7"
$PN"A40"60;
"PERN7"
$PN"A39"61;
"GND_A38"
$PN"A38"14;
"PERP6"
$PN"A37"43;
"PERN6"
$PN"A36"48;
"GND_A35"
$PN"A35"14;
"PERP5"
$PN"A34"44;
"PERN5"
$PN"A33"47;
"GND_A32"
$PN"A32"14;
"PERP4"
$PN"A31"41;
"PERN4"
$PN"A30"113;
"GND_A29"
$PN"A29"14;
"GND_A28"
$PN"A28"14;
"PERP3"
$PN"A27"39;
"PERN3"
$PN"A26"64;
"GND_A25"
$PN"A25"14;
"PERP2"
$PN"A24"123;
"PERN2"
$PN"A23"124;
"GND_A22"
$PN"A22"14;
"PERP1"
$PN"A21"62;
"PERN1"
$PN"A20"63;
"GND_A19"
$PN"A19"14;
"PERP0"
$PN"A18"67;
"PERN0"
$PN"A17"66;
"GND_A16"
$PN"A16"14;
"REFCLKP1"
$PN"A15"45;
"REFCLKN1"
$PN"A14"90;
"GND_A13"
$PN"A13"14;
"PRSNTB2# \B"
$PN"A12"91;
"PERST1# \B"
$PN"A11"92;
"PRSNTA# \B"
$PN"A10"93;
"SMRST# \B"
$PN"A9"25;
"SMDAT"
$PN"A8"31;
"SMCLK"
$PN"A7"40;
"GND_A6"
$PN"A6"14;
"GND_A5"
$PN"A5"14;
"GND_A4"
$PN"A4"14;
"GND_A3"
$PN"A3"14;
"GND_A2"
$PN"A2"14;
"GND_A1"
$PN"A1"14;
"RBT_CLK_IN"
$PN"OA14"22;
"GND_OA13"
$PN"OA13"14;
"REFCLKP3"
$PN"OA12"21;
"REFCLKN3"
$PN"OA11"20;
"GND_OA10"
$PN"OA10"14;
"RBT_TXD0"
$PN"OA9"121;
"RBT_TXD1"
$PN"OA8"94;
"RBT_TX_EN"
$PN"OA7"120;
"SLOT_ID1"
$PN"OA6"119;
"RBT_ARB_OUT"
$PN"OA5"122;
"RBT_ARB_IN"
$PN"OA4"118;
"WAKE# \B"
$PN"OA3"30;
"PERST3# \B"
$PN"OA2"29;
"PERST2# \B"
$PN"OA1"28;
"PETN12"
$PN"B56"70;
"GND_B55"
$PN"B55"12;
"PETP11"
$PN"B54"81;
"PETN11"
$PN"B53"79;
"GND_B52"
$PN"B52"12;
"PETP10"
$PN"B51"78;
"PETN10"
$PN"B50"77;
"GND_B49"
$PN"B49"12;
"PETP9"
$PN"B48"97;
"PETN9"
$PN"B47"76;
"GND_B46"
$PN"B46"12;
"PETP8"
$PN"B45"96;
"PETN8"
$PN"B44"95;
"GND_B43"
$PN"B43"12;
"PRSNTB0# \B"
$PN"B42"111;
"GND_B41"
$PN"B41"12;
"PETP7"
$PN"B40"112;
"PETN7"
$PN"B39"110;
"GND_B38"
$PN"B38"12;
"PETP6"
$PN"B37"109;
"PETN6"
$PN"B36"101;
"GND_B35"
$PN"B35"12;
"PETP5"
$PN"B34"108;
"PETN5"
$PN"B33"68;
"GND_B32"
$PN"B32"12;
"PETP4"
$PN"B31"107;
"PETN4"
$PN"B30"114;
"GND_B29"
$PN"B29"12;
"GND_B28"
$PN"B28"12;
"PETP3"
$PN"B27"106;
"PETN3"
$PN"B26"105;
"GND_B25"
$PN"B25"12;
"PETP2"
$PN"B24"104;
"PETN2"
$PN"B23"102;
"GND_B22"
$PN"B22"12;
"PETP1"
$PN"B21"103;
"PETN1"
$PN"B20"115;
"GND_B19"
$PN"B19"12;
"PETP0"
$PN"B18"116;
"PETN0"
$PN"B17"117;
"GND_B16"
$PN"B16"12;
"REFCLKP0"
$PN"B15"129;
"REFCLKN0"
$PN"B14"126;
"GND_B13"
$PN"B13"12;
"AUX_PWR_EN"
$PN"B12"133;
"+3.3V_EDGE"
$PN"B11"6;
"PERST0# \B"
$PN"B10"32;
"BIF2# \B"
$PN"B9"131;
"BIF1# \B"
$PN"B8"130;
"BIF0# \B"
$PN"B7"146;
"+12V_EDGE_B6"
$PN"B6"3;
"+12V_EDGE_B5"
$PN"B5"3;
"+12V_EDGE_B4"
$PN"B4"3;
"+12V_EDGE_B3"
$PN"B3"3;
"+12V_EDGE_B2"
$PN"B2"3;
"+12V_EDGE_B1"
$PN"B1"3;
"RBT_CRS_DV"
$PN"OB14"138;
"GND_OB13"
$PN"OB13"12;
"REFCLKP2"
$PN"OB12"137;
"REFCLKN2"
$PN"OB11"136;
"GND_OB10"
$PN"OB10"12;
"RBT_RXD0"
$PN"OB9"135;
"RBT_RXD1"
$PN"OB8"134;
"SLOT_ID0"
$PN"OB7"139;
"CLK"
$PN"OB6"140;
"DATA_OUT"
$PN"OB5"141;
"DATA_IN"
$PN"OB4"142;
"LD# \B"
$PN"OB3"143;
"MAIN_PWR_EN"
$PN"OB2"26;
"NIC_PWR_GOOD"
$PN"OB1"27;
%"Q_RES"
"2","(-4325,1725)","0","pure_quanta","I2";
;
PART_NUMBER"CS24702FB06"
VALUE"4.7K"
WATTAGE"1/16W"
TOLERANCE"1%"
MATERIAL"CHIP"
PACK_TYPE"0402LF"
$LOCATION"R410"
CDS_LIB"pure_quanta"
CDS_LOCATION"R410"
$SEC"1"
CDS_SEC"1";
"A"
$PN"1"36;
"B"
$PN"2"9;
%"TAP"
"1","(-1750,3350)","2","standard","I20";
;
CDS_LIB"standard"
BODY_TYPE"PLUMBING"
HDL_TAP"TRUE";
"B \NAC \NWC"19;
"S \NAC"
BN"12"70;
%"TAP"
"1","(-1600,5500)","2","standard","I202";
;
CDS_LIB"standard"
BODY_TYPE"PLUMBING"
HDL_TAP"TRUE";
"B \NAC \NWC"18;
"S \NAC"
BN"0"117;
%"TAP"
"1","(-1750,5450)","2","standard","I203";
;
CDS_LIB"standard"
BODY_TYPE"PLUMBING"
HDL_TAP"TRUE";
"B \NAC \NWC"19;
"S \NAC"
BN"0"116;
%"TAP"
"1","(900,5450)","0","standard","I205";
;
CDS_LIB"standard"
BODY_TYPE"PLUMBING"
HDL_TAP"TRUE";
"B \NAC \NWC"16;
"S \NAC"
BN"0"67;
%"TAP"
"1","(750,5500)","0","standard","I206";
;
CDS_LIB"standard"
BODY_TYPE"PLUMBING"
HDL_TAP"TRUE";
"B \NAC \NWC"17;
"S \NAC"
BN"0"66;
%"TAP"
"1","(-1750,3650)","2","standard","I21";
;
CDS_LIB"standard"
BODY_TYPE"PLUMBING"
HDL_TAP"TRUE";
"B \NAC \NWC"19;
"S \NAC"
BN"10"77;
%"Q_RES"
"1","(-775,1625)","0","pure_quanta","I212";
;
PART_NUMBER"CS21002FB06"
PACK_TYPE"0402LF"
TOLERANCE"1%"
WATTAGE"1/16W"
VALUE"1K"
MATERIAL"CHIP"
LOCATION"R423"
CDS_LIB"pure_quanta"
$SEC"1"
CDS_SEC"1";
"B"
$PN"2"5;
"A"
$PN"1"148;
%"Q_RES"
"1","(-775,1450)","0","pure_quanta","I215";
;
PART_NUMBER"CS31002FB08"
MATERIAL"CHIP"
TOLERANCE"1%"
VALUE"10K"
LOCATION"R422"
CDS_LIB"pure_quanta"
PACK_TYPE"0402LF"
WATTAGE"1/16W"
$SEC"1"
CDS_SEC"1";
"B"
$PN"2"8;
"A"
$PN"1"147;
%"Q_RES"
"1","(-775,1800)","0","pure_quanta","I217";
;
PART_NUMBER"CS31002FB08"
MATERIAL"CHIP"
TOLERANCE"1%"
VALUE"10K"
LOCATION"R421"
PACK_TYPE"0402LF"
WATTAGE"1/16W"
CDS_LIB"pure_quanta"
$SEC"1"
CDS_SEC"1";
"B"
$PN"2"5;
"A"
$PN"1"99;
%"Q_RES"
"1","(-775,1975)","0","pure_quanta","I218";
;
PART_NUMBER"CS21002FB06"
VALUE"1K"
TOLERANCE"1%"
WATTAGE"1/16W"
PACK_TYPE"0402LF"
MATERIAL"CHIP"
LOCATION"R420"
CDS_LIB"pure_quanta"
$SEC"1"
CDS_SEC"1";
"B"
$PN"2"5;
"A"
$PN"1"100;
%"Q_RES"
"1","(1750,5950)","0","pure_quanta","I220";
;
PART_NUMBER"CS12002FB06"
MATERIAL"CHIP"
TOLERANCE"1%"
VALUE"200"
PACK_TYPE"0402LF"
WATTAGE"1/16W"
LOCATION"R425"
CDS_LIB"pure_quanta"
LOCATION"R425"
$SEC"1"
CDS_SEC"1";
"B"
$PN"2"24;
"A"
$PN"1"31;
%"UNIVERSAL_GND"
"1","(-1375,2500)","0","logical_power","I25";
;
CDS_LIB"logical_power"
HDL_POWER"GND"
ROOM"IO_SLOT";
"A"12;
%"TAP"
"1","(-1600,3000)","2","standard","I28";
;
CDS_LIB"standard"
BODY_TYPE"PLUMBING"
HDL_TAP"TRUE";
"B \NAC \NWC"18;
"S \NAC"
BN"14"42;
%"UNIVERSAL_GND"
"1","(-3850,1500)","0","logical_power","I3";
;
CDS_LIB"logical_power"
HDL_POWER"GND"
ROOM"IO_SLOT";
"A"10;
%"TAP"
"1","(-1600,3300)","2","standard","I30";
;
CDS_LIB"standard"
BODY_TYPE"PLUMBING"
HDL_TAP"TRUE";
"B \NAC \NWC"18;
"S \NAC"
BN"12"69;
%"TAP"
"1","(-1600,3600)","2","standard","I32";
;
CDS_LIB"standard"
BODY_TYPE"PLUMBING"
HDL_TAP"TRUE";
"B \NAC \NWC"18;
"S \NAC"
BN"10"78;
%"UNIVERSAL_GND"
"1","(-4675,4325)","0","logical_power","I34";
;
CDS_LIB"logical_power"
HDL_POWER"GND";
"A"11;
%"Q_RES"
"1","(-4250,4425)","0","pure_quanta","I35";
;
PART_NUMBER"CS41002FB09"
PACK_TYPE"0402LF"
TOLERANCE"1%"
MATERIAL"CHIP"
VALUE"100K"
WATTAGE"1/16W"
$LOCATION"R3132"
CDS_LIB"pure_quanta"
CDS_LOCATION"R3132"
$SEC"1"
CDS_SEC"1";
"B"
$PN"2"132;
"A"
$PN"1"11;
%"Q_RES"
"1","(-4250,4625)","0","pure_quanta","I36";
;
PART_NUMBER"CS31002FB08"
VALUE"10K"
TOLERANCE"1%"
MATERIAL"CHIP"
$LOCATION"R1930"
CDS_LIB"pure_quanta"
WATTAGE"1/16W"
PACK_TYPE"0402LF"
CDS_LOCATION"R1930"
$SEC"1"
CDS_SEC"1";
"B"
$PN"2"145;
"A"
$PN"1"11;
%"Q_RES"
"1","(-4250,4725)","0","pure_quanta","I37";
;
PART_NUMBER"CS31002FB08"
PACK_TYPE"0402LF"
TOLERANCE"1%"
VALUE"10K"
MATERIAL"CHIP"
WATTAGE"1/16W"
$LOCATION"R1929"
CDS_LIB"pure_quanta"
CDS_LOCATION"R1929"
$SEC"1"
CDS_SEC"1";
"B"
$PN"2"34;
"A"
$PN"1"11;
%"Q_RES"
"2","(-3850,1725)","0","pure_quanta","I4";
;
PART_NUMBER"CS24702FB06"
VALUE"4.7K"
WATTAGE"1/16W"
TOLERANCE"1%"
MATERIAL"CHIP"
PACK_TYPE"0402LF"
$LOCATION"R415"
CDS_LIB"pure_quanta"
CDS_LOCATION"R415"
$SEC"1"
CDS_SEC"1";
"A"
$PN"1"35;
"B"
$PN"2"10;
%"Q_RES"
"2","(-4325,2250)","0","pure_quanta","I5";
;
PART_NUMBER"CS24702FB06"
TOLERANCE"1%"
VALUE"4.7K"
MATERIAL"EMPTY"
PACK_TYPE"0402LF"
WATTAGE"1/16W"
$LOCATION"R409"
CDS_LIB"pure_quanta"
CDS_LOCATION"R409"
$SEC"1"
CDS_SEC"1";
"A"
$PN"1"1;
"B"
$PN"2"36;
%"Q_RES"
"1","(-2900,5750)","0","pure_quanta","I51";
;
PART_NUMBER"CS00002JB13"
PACK_TYPE"0402LF"
VALUE"0"
TOLERANCE"5%"
$LOCATION"R1671"
WATTAGE"1/16W"
MATERIAL"CHIP"
CDS_LIB"pure_quanta"
CDS_LOCATION"R1671"
$SEC"1"
CDS_SEC"1";
"B"
$PN"2"133;
"A"
$PN"1"33;
%"Q_RES"
"1","(-2900,5900)","0","pure_quanta","I52";
;
PART_NUMBER"CS00002JB13"
TOLERANCE"5%"
PACK_TYPE"0402LF"
VALUE"0"
$LOCATION"R418"
CDS_LIB"pure_quanta"
MATERIAL"CHIP"
WATTAGE"1/16W"
CDS_LOCATION"R418"
$SEC"1"
CDS_SEC"1";
"B"
$PN"2"131;
"A"
$PN"1"128;
%"Q_RES"
"1","(-2900,5950)","0","pure_quanta","I53";
;
PART_NUMBER"CS00002JB13"
VALUE"0"
TOLERANCE"5%"
PACK_TYPE"0402LF"
$LOCATION"R417"
WATTAGE"1/16W"
MATERIAL"CHIP"
CDS_LIB"pure_quanta"
CDS_LOCATION"R417"
$SEC"1"
CDS_SEC"1";
"B"
$PN"2"130;
"A"
$PN"1"127;
%"Q_RES"
"1","(-2900,6000)","0","pure_quanta","I54";
;
PART_NUMBER"CS00002JB13"
MATERIAL"CHIP"
WATTAGE"1/16W"
TOLERANCE"5%"
VALUE"0"
PACK_TYPE"0402LF"
$LOCATION"R416"
CDS_LIB"pure_quanta"
CDS_LOCATION"R416"
$SEC"1"
CDS_SEC"1";
"B"
$PN"2"146;
"A"
$PN"1"125;
%"Q_RES"
"1","(-2900,7050)","0","pure_quanta","I58";
;
PART_NUMBER"CS00002JB13"
PACK_TYPE"0402LF"
VALUE"0"
TOLERANCE"5%"
$LOCATION"R429"
MATERIAL"CHIP"
WATTAGE"1/16W"
CDS_LIB"pure_quanta"
CDS_LOCATION"R429"
$SEC"1"
CDS_SEC"1";
"B"
$PN"2"26;
"A"
$PN"1"144;
%"TAP"
"1","(-1750,3950)","2","standard","I59";
;
CDS_LIB"standard"
BODY_TYPE"PLUMBING"
HDL_TAP"TRUE";
"B \NAC \NWC"19;
"S \NAC"
BN"8"95;
%"Q_RES"
"2","(-3850,2250)","0","pure_quanta","I6";
;
PART_NUMBER"CS24702FB06"
WATTAGE"1/16W"
MATERIAL"EMPTY"
TOLERANCE"1%"
VALUE"4.7K"
PACK_TYPE"0402LF"
$LOCATION"R414"
CDS_LIB"pure_quanta"
CDS_LOCATION"R414"
$SEC"1"
CDS_SEC"1";
"A"
$PN"1"1;
"B"
$PN"2"35;
%"TAP"
"1","(-1750,4450)","2","standard","I62";
;
CDS_LIB"standard"
BODY_TYPE"PLUMBING"
HDL_TAP"TRUE";
"B \NAC \NWC"19;
"S \NAC"
BN"6"101;
%"TAP"
"1","(-1750,4750)","2","standard","I63";
;
CDS_LIB"standard"
BODY_TYPE"PLUMBING"
HDL_TAP"TRUE";
"B \NAC \NWC"19;
"S \NAC"
BN"4"114;
%"TAP"
"1","(-1750,5200)","2","standard","I66";
;
CDS_LIB"standard"
BODY_TYPE"PLUMBING"
HDL_TAP"TRUE";
"B \NAC \NWC"19;
"S \NAC"
BN"2"102;
%"TAP"
"1","(-1600,4400)","2","standard","I69";
;
CDS_LIB"standard"
BODY_TYPE"PLUMBING"
HDL_TAP"TRUE";
"B \NAC \NWC"18;
"S \NAC"
BN"6"109;
%"UNIVERSAL_POWER"
"1","(-4325,2550)","0","logical_power","I7";
;
HDL_POWER"P3V3_OCP_SFF"
CDS_LIB"logical_power";
"A"1;
%"TAP"
"1","(-1600,4700)","2","standard","I70";
;
CDS_LIB"standard"
BODY_TYPE"PLUMBING"
HDL_TAP"TRUE";
"B \NAC \NWC"18;
"S \NAC"
BN"4"107;
%"TAP"
"1","(-1600,5150)","2","standard","I73";
;
CDS_LIB"standard"
BODY_TYPE"PLUMBING"
HDL_TAP"TRUE";
"B \NAC \NWC"18;
"S \NAC"
BN"2"104;
%"UNIVERSAL_GND"
"1","(-225,1325)","0","logical_power","I88";
;
CDS_LIB"logical_power"
HDL_POWER"GND"
ROOM"IO_SLOT";
"A"8;
%"Q_CAP"
"1","(800,1750)","0","pure_quanta","I89";
;
PART_NUMBER"CH6223MEA00"
MATERIAL"X6S"
PACK_TYPE"C0805"
TOLERANCE"20%"
VOLTAGE"16V"
VALUE"22UF"
$LOCATION"C1213"
CDS_LIB"pure_quanta"
CDS_LOCATION"C1213"
$SEC"1"
CDS_SEC"1";
"B"
$PN"2"15;
"A"
$PN"1"4;
%"Q_CAP"
"1","(1075,1750)","0","pure_quanta","I90";
;
PART_NUMBER"CH6223MEA00"
PACK_TYPE"C0805"
VALUE"22UF"
TOLERANCE"20%"
MATERIAL"X6S"
VOLTAGE"16V"
$LOCATION"C1232"
CDS_LIB"pure_quanta"
CDS_LOCATION"C1232"
$SEC"1"
CDS_SEC"1";
"B"
$PN"2"15;
"A"
$PN"1"4;
%"Q_CAP"
"1","(1475,1750)","0","pure_quanta","I91";
;
PART_NUMBER"CH4104K1B00"
TOLERANCE"10%"
VOLTAGE"25V"
VALUE"0.1UF"
MATERIAL"X7R"
PACK_TYPE"0402"
$LOCATION"C1233"
CDS_LIB"pure_quanta"
CDS_LOCATION"C1233"
$SEC"1"
CDS_SEC"1";
"B"
$PN"2"15;
"A"
$PN"1"4;
%"UNIVERSAL_POWER"
"1","(-225,2125)","0","logical_power","I92";
;
HDL_POWER"P3V3_OCP_SFF"
CDS_LIB"logical_power";
"A"5;
%"UNIVERSAL_POWER"
"1","(800,2100)","0","logical_power","I93";
;
HDL_POWER"P12V_OCP_SFF"
CDS_LIB"logical_power";
"A"4;
%"UNIVERSAL_GND"
"1","(550,2225)","0","logical_power","I94";
;
CDS_LIB"logical_power"
HDL_POWER"GND"
ROOM"IO_SLOT";
"A"14;
%"TAP"
"1","(750,2850)","0","standard","I95";
;
CDS_LIB"standard"
BODY_TYPE"PLUMBING"
HDL_TAP"TRUE";
"B \NAC \NWC"17;
"S \NAC"
BN"15"74;
%"TAP"
"1","(900,2900)","0","standard","I96";
;
CDS_LIB"standard"
BODY_TYPE"PLUMBING"
HDL_TAP"TRUE";
"B \NAC \NWC"16;
"S \NAC"
BN"15"75;
%"TAP"
"1","(750,3000)","0","standard","I97";
;
CDS_LIB"standard"
BODY_TYPE"PLUMBING"
HDL_TAP"TRUE";
"B \NAC \NWC"17;
"S \NAC"
BN"14"72;
%"TAP"
"1","(750,3150)","0","standard","I98";
;
CDS_LIB"standard"
BODY_TYPE"PLUMBING"
HDL_TAP"TRUE";
"B \NAC \NWC"17;
"S \NAC"
BN"13"53;
%"TAP"
"1","(750,3300)","0","standard","I99";
;
CDS_LIB"standard"
BODY_TYPE"PLUMBING"
HDL_TAP"TRUE";
"B \NAC \NWC"17;
"S \NAC"
BN"12"37;
END.
